# S9S_MB_2U (Grand Teton) — schematic netlist excerpt (pin names and nets, part order shuffled) for the footprints in the layout excerpt that follows; sources: Cadence DE-HDL packaged netlist, KiCad conversion of 03242023_DA0F0TMBIJ0_F0T_Motherboard_J_brd_V01_OCP.brd

R4  Q_RES  200 1% CHIP  pkg 0402LF  page 13 : A = JTAG_MUX_CPU0_GTL_TDI ; B = JTAG_DBP_CPU0_GTL_R_TDI
PR1805  Q_RES  0 5% CHIP  pkg 0402LF  page 297 : A = PVCCD_HV_CPU1_VOS ; B = PVCCD_HV_CPU1

(kicad_pcb
	(version 20260206)
	(generator "pcbnew")
	(generator_version "10.0")
	(general
		(thickness 1.6)
		(legacy_teardrops no)
	)
	(paper "A4")
	(title_block
		(title "03242023_DA0F0TMBIJ0_F0T_Motherboard_J_brd_V01_OCP.brd")
		(comment 1 "Grand Teton / footprints 5397-5398 of 6105")
	)
	(layers
		(0 "F.Cu" signal "TOP")
		(4 "In1.Cu" signal "GND")
		(6 "In2.Cu" signal "IN1")
		(8 "In3.Cu" signal "GND1")
		(10 "In4.Cu" signal "IN2")
		(12 "In5.Cu" signal "GND2")
		(14 "In6.Cu" signal "IN3")
		(16 "In7.Cu" signal "GND3")
		(18 "In8.Cu" signal "VCC")
		(20 "In9.Cu" signal "VCC1")
		(22 "In10.Cu" signal "GND4")
		(24 "In11.Cu" signal "IN4")
		(26 "In12.Cu" signal "GND5")
		(28 "In13.Cu" signal "IN5")
		(30 "In14.Cu" signal "GND6")
		(32 "In15.Cu" signal "IN6")
		(34 "In16.Cu" signal "GND7")
		(2 "B.Cu" signal "BOTTOM")
		(9 "F.Adhes" user "F.Adhesive")
		(11 "B.Adhes" user "B.Adhesive")
		(13 "F.Paste" user "Package Geometry/Pastemask Top")
		(15 "B.Paste" user "Package Geometry/Pastemask Bottom")
		(5 "F.SilkS" user "Ref Des/Silkscreen Top")
		(7 "B.SilkS" user "Ref Des/Silkscreen Bottom")
		(1 "F.Mask" user "Board Geometry/Soldermask Top")
		(3 "B.Mask" user "Board Geometry/Soldermask Bottom")
		(17 "Dwgs.User" user "User.Drawings")
		(19 "Cmts.User" user "User.Comments")
		(21 "Eco1.User" user "User.Eco1")
		(23 "Eco2.User" user "User.Eco2")
		(25 "Edge.Cuts" user "Board Geometry/Outline")
		(27 "Margin" user)
		(31 "F.CrtYd" user "Package Geometry/Place Bound Top")
		(29 "B.CrtYd" user "Package Geometry/Place Bound Bottom")
		(35 "F.Fab" user "Ref Des/Assembly Top")
		(33 "B.Fab" user "Ref Des/Assembly Bottom")
	)
	(footprint ""
		(layer "B.Cu")
		(at 52.335684 -161.260028)
		(property "Reference" "PR1805"
			(at 0 0 0)
			(layer "B.SilkS")
			(hide yes)
			(effects
				(font
					(size 1.27 1.27)
				)
				(justify mirror)
			)
		)
		(property "Value" ""
			(at 0 0 0)
			(layer "B.Fab")
			(effects
				(font
					(size 1.27 1.27)
				)
				(justify mirror)
			)
		)
		(duplicate_pad_numbers_are_jumpers no)
		(fp_line
			(start -0.7874 -0.4064)
			(end -0.7874 0.4064)
			(stroke
				(width 0.1524)
				(type default)
			)
			(layer "B.SilkS")
		)
		(fp_line
			(start -0.7874 0.4064)
			(end 0.7874 0.4064)
			(stroke
				(width 0.1524)
				(type default)
			)
			(layer "B.SilkS")
		)
		(fp_line
			(start 0.7874 -0.4064)
			(end -0.7874 -0.4064)
			(stroke
				(width 0.1524)
				(type default)
			)
			(layer "B.SilkS")
		)
		(fp_line
			(start 0.7874 0.4064)
			(end 0.7874 -0.4064)
			(stroke
				(width 0.1524)
				(type default)
			)
			(layer "B.SilkS")
		)
		(fp_line
			(start -0.67945 -0.3048)
			(end -0.67945 0.3048)
			(stroke
				(width 0.1)
				(type default)
			)
			(layer "B.Fab")
		)
		(fp_line
			(start -0.67945 0.3048)
			(end -0.120396 0.3048)
			(stroke
				(width 0.1)
				(type default)
			)
			(layer "B.Fab")
		)
		(fp_line
			(start -0.12065 -0.3048)
			(end -0.67945 -0.3048)
			(stroke
				(width 0.1)
				(type default)
			)
			(layer "B.Fab")
		)
		(fp_line
			(start -0.12065 -0.2794)
			(end -0.12065 -0.3048)
			(stroke
				(width 0.1)
				(type default)
			)
			(layer "B.Fab")
		)
		(fp_line
			(start -0.120396 0.2794)
			(end 0.12065 0.2794)
			(stroke
				(width 0.1)
				(type default)
			)
			(layer "B.Fab")
		)
		(fp_line
			(start -0.120396 0.3048)
			(end -0.120396 0.2794)
			(stroke
				(width 0.1)
				(type default)
			)
			(layer "B.Fab")
		)
		(fp_line
			(start 0.12065 -0.305054)
			(end 0.12065 -0.2794)
			(stroke
				(width 0.1)
				(type default)
			)
			(layer "B.Fab")
		)
		(fp_line
			(start 0.12065 -0.2794)
			(end -0.12065 -0.2794)
			(stroke
				(width 0.1)
				(type default)
			)
			(layer "B.Fab")
		)
		(fp_line
			(start 0.12065 0.2794)
			(end 0.12065 0.3048)
			(stroke
				(width 0.1)
				(type default)
			)
			(layer "B.Fab")
		)
		(fp_line
			(start 0.12065 0.3048)
			(end 0.67945 0.3048)
			(stroke
				(width 0.1)
				(type default)
			)
			(layer "B.Fab")
		)
		(fp_line
			(start 0.67945 -0.305054)
			(end 0.12065 -0.305054)
			(stroke
				(width 0.1)
				(type default)
			)
			(layer "B.Fab")
		)
		(fp_line
			(start 0.67945 0.3048)
			(end 0.67945 -0.305054)
			(stroke
				(width 0.1)
				(type default)
			)
			(layer "B.Fab")
		)
		(pad "1" smd circle
			(at 0.40005 0 180)
			(size 0 0)
			(layers "B.Cu" "B.Mask" "B.Paste")
			(net "PVCCD_HV_CPU1_VOS")
		)
		(pad "2" smd circle
			(at -0.40005 0 180)
			(size 0 0)
			(layers "B.Cu" "B.Mask" "B.Paste")
			(net "PVCCD_HV_CPU1")
		)
	)
	(footprint ""
		(layer "B.Cu")
		(at 338.911692 -187.998608 -90)
		(property "Reference" "R4"
			(at 0 0 90)
			(layer "B.SilkS")
			(hide yes)
			(effects
				(font
					(size 1.27 1.27)
				)
				(justify mirror)
			)
		)
		(property "Value" ""
			(at 0 0 90)
			(layer "B.Fab")
			(effects
				(font
					(size 1.27 1.27)
				)
				(justify mirror)
			)
		)
		(duplicate_pad_numbers_are_jumpers no)
		(fp_line
			(start -0.7874 0.4064)
			(end 0.7874 0.4064)
			(stroke
				(width 0.1524)
				(type default)
			)
			(layer "B.SilkS")
		)
		(fp_line
			(start 0.7874 0.4064)
			(end 0.7874 -0.4064)
			(stroke
				(width 0.1524)
				(type default)
			)
			(layer "B.SilkS")
		)
		(fp_line
			(start -0.7874 -0.4064)
			(end -0.7874 0.4064)
			(stroke
				(width 0.1524)
				(type default)
			)
			(layer "B.SilkS")
		)
		(fp_line
			(start 0.7874 -0.4064)
			(end -0.7874 -0.4064)
			(stroke
				(width 0.1524)
				(type default)
			)
			(layer "B.SilkS")
		)
		(fp_line
			(start -0.67945 0.3048)
			(end -0.120396 0.3048)
			(stroke
				(width 0.1)
				(type default)
			)
			(layer "B.Fab")
		)
		(fp_line
			(start -0.120396 0.3048)
			(end -0.120396 0.2794)
			(stroke
				(width 0.1)
				(type default)
			)
			(layer "B.Fab")
		)
		(fp_line
			(start 0.12065 0.3048)
			(end 0.67945 0.3048)
			(stroke
				(width 0.1)
				(type default)
			)
			(layer "B.Fab")
		)
		(fp_line
			(start 0.67945 0.3048)
			(end 0.67945 -0.305054)
			(stroke
				(width 0.1)
				(type default)
			)
			(layer "B.Fab")
		)
		(fp_line
			(start -0.120396 0.2794)
			(end 0.12065 0.2794)
			(stroke
				(width 0.1)
				(type default)
			)
			(layer "B.Fab")
		)
		(fp_line
			(start 0.12065 0.2794)
			(end 0.12065 0.3048)
			(stroke
				(width 0.1)
				(type default)
			)
			(layer "B.Fab")
		)
		(fp_line
			(start -0.12065 -0.2794)
			(end -0.12065 -0.3048)
			(stroke
				(width 0.1)
				(type default)
			)
			(layer "B.Fab")
		)
		(fp_line
			(start 0.12065 -0.2794)
			(end -0.12065 -0.2794)
			(stroke
				(width 0.1)
				(type default)
			)
			(layer "B.Fab")
		)
		(fp_line
			(start -0.67945 -0.3048)
			(end -0.67945 0.3048)
			(stroke
				(width 0.1)
				(type default)
			)
			(layer "B.Fab")
		)
		(fp_line
			(start -0.12065 -0.3048)
			(end -0.67945 -0.3048)
			(stroke
				(width 0.1)
				(type default)
			)
			(layer "B.Fab")
		)
		(fp_line
			(start 0.12065 -0.305054)
			(end 0.12065 -0.2794)
			(stroke
				(width 0.1)
				(type default)
			)
			(layer "B.Fab")
		)
		(fp_line
			(start 0.67945 -0.305054)
			(end 0.12065 -0.305054)
			(stroke
				(width 0.1)
				(type default)
			)
			(layer "B.Fab")
		)
		(pad "1" smd circle
			(at 0.40005 0 90)
			(size 0 0)
			(layers "B.Cu" "B.Mask" "B.Paste")
			(net "JTAG_MUX_CPU0_GTL_TDI")
		)
		(pad "2" smd circle
			(at -0.40005 0 90)
			(size 0 0)
			(layers "B.Cu" "B.Mask" "B.Paste")
			(net "JTAG_DBP_CPU0_GTL_R_TDI")
		)
	)
)
